# S9S_MB_2U (Grand Teton) — schematic netlist excerpt (pin names and nets, part order shuffled) for the footprints in the layout excerpt that follows; sources: Cadence DE-HDL packaged netlist, KiCad conversion of 03242023_DA0F0TMBIJ0_F0T_Motherboard_J_brd_V01_OCP.brd

C967  Q_CAP  10UF 6.3V 20% X6S  pkg C0402  page 74 : A = PVCCIN_CPU0 ; B = GND
R1010  Q_RES  0 5% CHIP  pkg 0402LF  page 209 : A = CLK_25M_CK440_ISCLK_REF_DP ; B = CLK_25M_PCH_REF_NS_DP

(kicad_pcb
	(version 20260206)
	(generator "pcbnew")
	(generator_version "10.0")
	(general
		(thickness 1.6)
		(legacy_teardrops no)
	)
	(paper "A4")
	(title_block
		(title "03242023_DA0F0TMBIJ0_F0T_Motherboard_J_brd_V01_OCP.brd")
		(comment 1 "Grand Teton / footprints 2394-2395 of 6105")
	)
	(layers
		(0 "F.Cu" signal "TOP")
		(4 "In1.Cu" signal "GND")
		(6 "In2.Cu" signal "IN1")
		(8 "In3.Cu" signal "GND1")
		(10 "In4.Cu" signal "IN2")
		(12 "In5.Cu" signal "GND2")
		(14 "In6.Cu" signal "IN3")
		(16 "In7.Cu" signal "GND3")
		(18 "In8.Cu" signal "VCC")
		(20 "In9.Cu" signal "VCC1")
		(22 "In10.Cu" signal "GND4")
		(24 "In11.Cu" signal "IN4")
		(26 "In12.Cu" signal "GND5")
		(28 "In13.Cu" signal "IN5")
		(30 "In14.Cu" signal "GND6")
		(32 "In15.Cu" signal "IN6")
		(34 "In16.Cu" signal "GND7")
		(2 "B.Cu" signal "BOTTOM")
		(9 "F.Adhes" user "F.Adhesive")
		(11 "B.Adhes" user "B.Adhesive")
		(13 "F.Paste" user "Package Geometry/Pastemask Top")
		(15 "B.Paste" user "Package Geometry/Pastemask Bottom")
		(5 "F.SilkS" user "Ref Des/Silkscreen Top")
		(7 "B.SilkS" user "Ref Des/Silkscreen Bottom")
		(1 "F.Mask" user "Board Geometry/Soldermask Top")
		(3 "B.Mask" user "Board Geometry/Soldermask Bottom")
		(17 "Dwgs.User" user "User.Drawings")
		(19 "Cmts.User" user "User.Comments")
		(21 "Eco1.User" user "User.Eco1")
		(23 "Eco2.User" user "User.Eco2")
		(25 "Edge.Cuts" user "Board Geometry/Outline")
		(27 "Margin" user)
		(31 "F.CrtYd" user "Package Geometry/Place Bound Top")
		(29 "B.CrtYd" user "Package Geometry/Place Bound Bottom")
		(35 "F.Fab" user "Ref Des/Assembly Top")
		(33 "B.Fab" user "Ref Des/Assembly Bottom")
	)
	(footprint ""
		(layer "F.Cu")
		(at 355.247448 -249.320304 -90)
		(property "Reference" "C967"
			(at 0 0 270)
			(layer "F.SilkS")
			(hide yes)
			(effects
				(font
					(size 1.27 1.27)
				)
			)
		)
		(property "Value" ""
			(at 0 0 270)
			(layer "F.Fab")
			(effects
				(font
					(size 1.27 1.27)
				)
			)
		)
		(duplicate_pad_numbers_are_jumpers no)
		(fp_line
			(start -0.7874 0.4064)
			(end -0.7874 -0.4064)
			(stroke
				(width 0.1524)
				(type default)
			)
			(layer "F.SilkS")
		)
		(fp_line
			(start 0.7874 0.4064)
			(end -0.7874 0.4064)
			(stroke
				(width 0.1524)
				(type default)
			)
			(layer "F.SilkS")
		)
		(fp_line
			(start -0.7874 -0.4064)
			(end 0.7874 -0.4064)
			(stroke
				(width 0.1524)
				(type default)
			)
			(layer "F.SilkS")
		)
		(fp_line
			(start 0.7874 -0.4064)
			(end 0.7874 0.4064)
			(stroke
				(width 0.1524)
				(type default)
			)
			(layer "F.SilkS")
		)
		(fp_line
			(start -0.67945 0.3048)
			(end -0.67945 -0.305054)
			(stroke
				(width 0.1)
				(type default)
			)
			(layer "F.Fab")
		)
		(fp_line
			(start -0.12065 0.3048)
			(end -0.67945 0.3048)
			(stroke
				(width 0.1)
				(type default)
			)
			(layer "F.Fab")
		)
		(fp_line
			(start 0.120396 0.3048)
			(end 0.120396 0.2794)
			(stroke
				(width 0.1)
				(type default)
			)
			(layer "F.Fab")
		)
		(fp_line
			(start 0.67945 0.3048)
			(end 0.120396 0.3048)
			(stroke
				(width 0.1)
				(type default)
			)
			(layer "F.Fab")
		)
		(fp_line
			(start -0.12065 0.2794)
			(end -0.12065 0.3048)
			(stroke
				(width 0.1)
				(type default)
			)
			(layer "F.Fab")
		)
		(fp_line
			(start 0.120396 0.2794)
			(end -0.12065 0.2794)
			(stroke
				(width 0.1)
				(type default)
			)
			(layer "F.Fab")
		)
		(fp_line
			(start -0.12065 -0.2794)
			(end 0.12065 -0.2794)
			(stroke
				(width 0.1)
				(type default)
			)
			(layer "F.Fab")
		)
		(fp_line
			(start 0.12065 -0.2794)
			(end 0.12065 -0.3048)
			(stroke
				(width 0.1)
				(type default)
			)
			(layer "F.Fab")
		)
		(fp_line
			(start 0.12065 -0.3048)
			(end 0.67945 -0.3048)
			(stroke
				(width 0.1)
				(type default)
			)
			(layer "F.Fab")
		)
		(fp_line
			(start 0.67945 -0.3048)
			(end 0.67945 0.3048)
			(stroke
				(width 0.1)
				(type default)
			)
			(layer "F.Fab")
		)
		(fp_line
			(start -0.67945 -0.305054)
			(end -0.12065 -0.305054)
			(stroke
				(width 0.1)
				(type default)
			)
			(layer "F.Fab")
		)
		(fp_line
			(start -0.12065 -0.305054)
			(end -0.12065 -0.2794)
			(stroke
				(width 0.1)
				(type default)
			)
			(layer "F.Fab")
		)
		(pad "1" smd circle
			(at -0.40005 0 270)
			(size 0 0)
			(layers "F.Cu" "F.Mask" "F.Paste")
			(net "PVCCIN_CPU0")
		)
		(pad "2" smd circle
			(at 0.40005 0 270)
			(size 0 0)
			(layers "F.Cu" "F.Mask" "F.Paste")
			(net "GND")
		)
	)
	(footprint ""
		(layer "F.Cu")
		(at 250.733306 -108.192824 90)
		(property "Reference" "R1010"
			(at 0 0 90)
			(layer "F.SilkS")
			(hide yes)
			(effects
				(font
					(size 1.27 1.27)
				)
			)
		)
		(property "Value" ""
			(at 0 0 90)
			(layer "F.Fab")
			(effects
				(font
					(size 1.27 1.27)
				)
			)
		)
		(duplicate_pad_numbers_are_jumpers no)
		(fp_line
			(start 0.7874 -0.4064)
			(end 0.7874 0.4064)
			(stroke
				(width 0.1524)
				(type default)
			)
			(layer "F.SilkS")
		)
		(fp_line
			(start -0.7874 -0.4064)
			(end 0.7874 -0.4064)
			(stroke
				(width 0.1524)
				(type default)
			)
			(layer "F.SilkS")
		)
		(fp_line
			(start 0.7874 0.4064)
			(end -0.7874 0.4064)
			(stroke
				(width 0.1524)
				(type default)
			)
			(layer "F.SilkS")
		)
		(fp_line
			(start -0.7874 0.4064)
			(end -0.7874 -0.4064)
			(stroke
				(width 0.1524)
				(type default)
			)
			(layer "F.SilkS")
		)
		(fp_line
			(start -0.12065 -0.305054)
			(end -0.12065 -0.2794)
			(stroke
				(width 0.1)
				(type default)
			)
			(layer "F.Fab")
		)
		(fp_line
			(start -0.67945 -0.305054)
			(end -0.12065 -0.305054)
			(stroke
				(width 0.1)
				(type default)
			)
			(layer "F.Fab")
		)
		(fp_line
			(start 0.67945 -0.3048)
			(end 0.67945 0.3048)
			(stroke
				(width 0.1)
				(type default)
			)
			(layer "F.Fab")
		)
		(fp_line
			(start 0.12065 -0.3048)
			(end 0.67945 -0.3048)
			(stroke
				(width 0.1)
				(type default)
			)
			(layer "F.Fab")
		)
		(fp_line
			(start 0.12065 -0.2794)
			(end 0.12065 -0.3048)
			(stroke
				(width 0.1)
				(type default)
			)
			(layer "F.Fab")
		)
		(fp_line
			(start -0.12065 -0.2794)
			(end 0.12065 -0.2794)
			(stroke
				(width 0.1)
				(type default)
			)
			(layer "F.Fab")
		)
		(fp_line
			(start 0.120396 0.2794)
			(end -0.12065 0.2794)
			(stroke
				(width 0.1)
				(type default)
			)
			(layer "F.Fab")
		)
		(fp_line
			(start -0.12065 0.2794)
			(end -0.12065 0.3048)
			(stroke
				(width 0.1)
				(type default)
			)
			(layer "F.Fab")
		)
		(fp_line
			(start 0.67945 0.3048)
			(end 0.120396 0.3048)
			(stroke
				(width 0.1)
				(type default)
			)
			(layer "F.Fab")
		)
		(fp_line
			(start 0.120396 0.3048)
			(end 0.120396 0.2794)
			(stroke
				(width 0.1)
				(type default)
			)
			(layer "F.Fab")
		)
		(fp_line
			(start -0.12065 0.3048)
			(end -0.67945 0.3048)
			(stroke
				(width 0.1)
				(type default)
			)
			(layer "F.Fab")
		)
		(fp_line
			(start -0.67945 0.3048)
			(end -0.67945 -0.305054)
			(stroke
				(width 0.1)
				(type default)
			)
			(layer "F.Fab")
		)
		(pad "1" smd circle
			(at -0.40005 0 90)
			(size 0 0)
			(layers "F.Cu" "F.Mask" "F.Paste")
			(net "CLK_25M_CK440_ISCLK_REF_DP")
		)
		(pad "2" smd circle
			(at 0.40005 0 90)
			(size 0 0)
			(layers "F.Cu" "F.Mask" "F.Paste")
			(net "CLK_25M_PCH_REF_NS_DP")
		)
	)
)
